# Barreleye G2-MB-EVT3-PROGRAM IC LIST-X02-20170223.xlsx — Barreleye-G2 MB (ic-programming-list)
| FOXCONN TECHNOLOGY GROUP |  |  |  |  |  |  |  |  |  |  |  |  |  |  |  |
| Program IC List |  |  |  |  |  |  |  |  |  |  |  |  |  |  |  |
| Phase | EVT3 | CUSTOMER |  | RACKSPACE | PWA CUSTOMER P/N |  | PWA FOXCONN P/N | TBD | PWA DESCRIPTION | Barreleye-G2 MB | PRODUCT CODE | PBA REV | X02 | DATE | 42782 |
| Location | Function | Source code version | Program Type | Bin File | Empty IC  FOXCONN PN | Empty IC  Supplier PN | Programmed IC  FOXCONN PN | CheckSUM | Program Spec | Source Code Release Date | From Whom | Comment |  |  |  |
| U37 | USB controller UPD720201, EEPROM | 0.0.0 | Off-line |  | 41050J100-233-G | MX25L5121EMC-20G | TBD | 005E79A3 |  | 42607 | SANSHIN.TW RENESAS |  |  |  |  |
| U46 | SATA Controller 88SE9235, FLASH | 0.0.0 | Off-line |  | 41050K700-233-G | MX25L4006EM2I-12G | TBD | 03B75FF7 |  | 42401 | Marvell |  |  |  |  |
| U_LOM1_ROM1 | LOM BCM5719,FLASH | 0.0.0 | Off-line |  | 41050W700-46Y-G | AT45DB081E-SHNHC-T | TBD | 05B5D2E9 |  | 42628 | Broadcom |  |  |  |  |
| U20 | BMC AST2500, 1Gb Flash | obmc-71526c28-4-g5d5303d2-dirty | Off-line |  | 410512F00-233-G | MX66L51235FMI-10G | TBD | 6DF4223C |  | 42782 | Google | For fixing EVT3 VCS issue |  |  |  |
| U24 | BMC AST2500, 64Mb Flash | N/A | NA | N/A | 41050DL00-233-G | MX25L6445EMI-10G | TBD |  |  |  | FXN |  |  |  |  |
| U21 | BIOS, 1Gb Flash | Bareeleye-G2 EVT | Off-line |  | 410512F00-233-G | MX66L51235FMI-10G | TBD | 9366B428 |  | 42789 | FXN | For EVT3 BIOS updated forfix CPU issue |  |  |  |
| U98 | VPD, EEPROM | EVT3 | Off-line |  | 410403P00-214-G | M24512-WMN6TP | TBD | 000362DE |  | 42776 | IBM | For EVT3 VPD updated |  |  |  |
| U30 | FRU, EEPROM | 0.0.0 | Off-line |  | 41040BT00-191-G | AT24C64D-SSHM-T | TBD | 00005900 |  | 42622 | FXN | Barreleye-G2 MB FRU |  |  |  |
| PAAU1,PBAU1,PAMU1,PBMU1,PAEU1,PAFU1,PBEU1,PBFU1 | VR Controller, ISL68137 | 0.0.1 | Vendor | Waiting for vendor to provide code | 320242200-230-G | ISL68137IRAZ-T | TBD | N/A |  |  | FXN |  |  |  |  |
| PANU1,PBNU1 | VIO VR, IR38064 | 0.0.1 | Vendor |  | 320147Q00-238-G | IR38064MTRPBF | TBD | 8874 |  | 42691 | FXN |  |  |  |  |
| U5 | Power Sequencer, UCD90160 | UCD90160-VCSoff-022117_1V05-10mS-3V3 | on-line |  | 320245T00-183-G | UCD90160RGCR-C09 | TBD | 01541B98 |  | 42787 | FXN | Updated for USB PCIe detect issue |  |  |  |
